(kicad_pcb
	(version 20241229)
	(generator "pcbnew")
	(generator_version "9.0")
	(general
		(thickness 1.62)
		(legacy_teardrops no)
	)
	(paper "A4")
	(title_block
		(title "OCuLink to 10GbE adapter")
		(date "2026-02-23")
		(rev "1.1.0")
		(company "Antmicro Ltd")
		(comment 1 "www.antmicro.com")
		(comment 9 "footprints 173-178 of 510")
	)
	(layers
		(0 "F.Cu" signal)
		(4 "In1.Cu" signal)
		(6 "In2.Cu" signal)
		(8 "In3.Cu" signal)
		(10 "In4.Cu" signal)
		(12 "In5.Cu" signal)
		(14 "In6.Cu" signal)
		(2 "B.Cu" signal)
		(9 "F.Adhes" user "F.Adhesive")
		(11 "B.Adhes" user "B.Adhesive")
		(13 "F.Paste" user)
		(15 "B.Paste" user)
		(5 "F.SilkS" user "F.Silkscreen")
		(7 "B.SilkS" user "B.Silkscreen")
		(1 "F.Mask" user)
		(3 "B.Mask" user)
		(17 "Dwgs.User" user "User.Drawings")
		(19 "Cmts.User" user "User.Comments")
		(21 "Eco1.User" user "User.Eco1")
		(23 "Eco2.User" user "User.Eco2")
		(25 "Edge.Cuts" user)
		(27 "Margin" user)
		(31 "F.CrtYd" user "F.Courtyard")
		(29 "B.CrtYd" user "B.Courtyard")
		(35 "F.Fab" user)
		(33 "B.Fab" user)
	)
	(footprint "antmicro-footprints:TP_SMD_0.75mm"
		(layer "F.Cu")
		(at 113.2 105.226 180)
		(property "Reference" "TP26"
			(at 0.8 -0.474 90)
			(layer "F.SilkS")
			(effects
				(font
					(size 0.7 0.7)
					(thickness 0.15)
				)
				(justify right top)
			)
		)
		(property "Value" "TP_0.75mm_SMD"
			(at 0 1.2 0)
			(layer "F.Fab")
			(hide yes)
			(effects
				(font
					(size 0.7 0.7)
					(thickness 0.15)
				)
				(justify right top)
			)
		)
		(property "Description" "SMT test point"
			(at 0 0 0)
			(layer "F.Fab")
			(hide yes)
			(effects
				(font
					(size 1.27 1.27)
					(thickness 0.15)
				)
			)
		)
		(property "MPN" ""
			(at 0 0 180)
			(unlocked yes)
			(layer "F.Fab")
			(hide yes)
			(effects
				(font
					(size 1 1)
					(thickness 0.15)
				)
			)
		)
		(property "Manufacturer" ""
			(at 0 0 180)
			(unlocked yes)
			(layer "F.Fab")
			(hide yes)
			(effects
				(font
					(size 1 1)
					(thickness 0.15)
				)
			)
		)
		(property "Author" "Antmicro"
			(at 0 0 180)
			(unlocked yes)
			(layer "F.Fab")
			(hide yes)
			(effects
				(font
					(size 1 1)
					(thickness 0.15)
				)
			)
		)
		(property "License" "Apache-2.0"
			(at 0 0 180)
			(unlocked yes)
			(layer "F.Fab")
			(hide yes)
			(effects
				(font
					(size 1 1)
					(thickness 0.15)
				)
			)
		)
		(sheetname "/Fan controller/")
		(sheetfile "fan-controller.kicad_sch")
		(attr exclude_from_pos_files exclude_from_bom dnp)
		(fp_circle
			(center 0 0)
			(end 0.475 0)
			(stroke
				(width 0.05)
				(type default)
			)
			(fill no)
			(layer "F.CrtYd")
		)
		(pad "1" smd circle
			(at 0 0 180)
			(size 0.75 0.75)
			(layers "F.Cu" "F.Mask")
			(net 388 "/Fan controller/+5V")
			(pinfunction "1")
			(pintype "passive")
		)
	)
	(footprint "antmicro-footprints:C_0603_1608Metric_EIA"
		(layer "F.Cu")
		(at 70.499998 75.839995 180)
		(descr "Capacitor SMD 0603, IPC-7351 Density Level A")
		(tags "Capacitor 0603")
		(property "Reference" "C3"
			(at 1.199998 0.339995 0)
			(layer "F.SilkS")
			(effects
				(font
					(size 0.7 0.7)
					(thickness 0.15)
				)
				(justify right top)
			)
		)
		(property "Value" "C_22u_16V_0603"
			(at -1.42757 1.770288 0)
			(layer "F.Fab")
			(hide yes)
			(effects
				(font
					(size 0.7 0.7)
					(thickness 0.15)
				)
				(justify right top)
			)
		)
		(property "Datasheet" "https://product.samsungsem.com/mlcc/CL10A226MO7JZN.do"
			(at 0 0 0)
			(layer "F.Fab")
			(hide yes)
			(effects
				(font
					(size 1.27 1.27)
					(thickness 0.15)
				)
			)
		)
		(property "Description" "SMD Multilayer Ceramic Capacitor"
			(at 0 0 0)
			(layer "F.Fab")
			(hide yes)
			(effects
				(font
					(size 1.27 1.27)
					(thickness 0.15)
				)
			)
		)
		(property "MPN" "CL10A226MO7JZNC"
			(at 0 0 180)
			(unlocked yes)
			(layer "F.Fab")
			(hide yes)
			(effects
				(font
					(size 1 1)
					(thickness 0.15)
				)
			)
		)
		(property "Manufacturer" "Samsung Electro-Mechanics"
			(at 0 0 180)
			(unlocked yes)
			(layer "F.Fab")
			(hide yes)
			(effects
				(font
					(size 1 1)
					(thickness 0.15)
				)
			)
		)
		(property "License" "Apache-2.0"
			(at 0 0 180)
			(unlocked yes)
			(layer "F.Fab")
			(hide yes)
			(effects
				(font
					(size 1 1)
					(thickness 0.15)
				)
			)
		)
		(property "Author" "Antmicro"
			(at 0 0 180)
			(unlocked yes)
			(layer "F.Fab")
			(hide yes)
			(effects
				(font
					(size 1 1)
					(thickness 0.15)
				)
			)
		)
		(property "Val" "22u"
			(at 0 0 180)
			(unlocked yes)
			(layer "F.Fab")
			(hide yes)
			(effects
				(font
					(size 1 1)
					(thickness 0.15)
				)
			)
		)
		(property "Voltage" "16V"
			(at 0 0 180)
			(unlocked yes)
			(layer "F.Fab")
			(hide yes)
			(effects
				(font
					(size 1 1)
					(thickness 0.15)
				)
			)
		)
		(property "Dielectric" ""
			(at 0 0 180)
			(unlocked yes)
			(layer "F.Fab")
			(hide yes)
			(effects
				(font
					(size 1 1)
					(thickness 0.15)
				)
			)
		)
		(property "Public" "False"
			(at 0 0 180)
			(unlocked yes)
			(layer "F.Fab")
			(hide yes)
			(effects
				(font
					(size 1 1)
					(thickness 0.15)
				)
			)
		)
		(sheetname "/Power/")
		(sheetfile "power.kicad_sch")
		(attr smd)
		(fp_line
			(start -0.15 0.55)
			(end 0.15 0.55)
			(stroke
				(width 0.15)
				(type solid)
			)
			(layer "F.SilkS")
		)
		(fp_line
			(start -0.15 -0.55)
			(end 0.15 -0.55)
			(stroke
				(width 0.15)
				(type solid)
			)
			(layer "F.SilkS")
		)
		(fp_rect
			(start -1.25 -0.65)
			(end 1.25 0.65)
			(stroke
				(width 0.05)
				(type solid)
			)
			(fill no)
			(layer "F.CrtYd")
		)
		(fp_rect
			(start -0.8 -0.45)
			(end 0.8 0.45)
			(stroke
				(width 0.15)
				(type solid)
			)
			(fill no)
			(layer "F.Fab")
		)
		(pad "1" smd roundrect
			(at -0.7 0 180)
			(size 0.8 1.1)
			(layers "F.Cu" "F.Mask" "F.Paste")
			(roundrect_rratio 0.2)
			(net 28 "GND")
			(pintype "passive")
		)
		(pad "2" smd roundrect
			(at 0.7 0 180)
			(size 0.8 1.1)
			(layers "F.Cu" "F.Mask" "F.Paste")
			(roundrect_rratio 0.2)
			(net 314 "VCC")
			(pintype "passive")
		)
	)
	(footprint "antmicro-footprints:C_0402_1005Metric"
		(layer "F.Cu")
		(at 118.33 103.87 -90)
		(descr "Capacitor SMD 0402")
		(tags "capacitor SMD 0402")
		(property "Reference" "C212"
			(at -1.39 -0.56 90)
			(layer "F.SilkS")
			(effects
				(font
					(size 0.7 0.7)
					(thickness 0.15)
				)
				(justify right top)
			)
		)
		(property "Value" "C_1u_25V_0402"
			(at -1.022927 2.155213 90)
			(layer "F.Fab")
			(effects
				(font
					(size 0.7 0.7)
					(thickness 0.15)
				)
				(justify right top)
			)
		)
		(property "Datasheet" "https://www.murata.com/products/productdetail?partno=GRM155R61E105KE11%23"
			(at 0 0 90)
			(layer "F.Fab")
			(hide yes)
			(effects
				(font
					(size 1.27 1.27)
					(thickness 0.15)
				)
			)
		)
		(property "Description" "SMD Multilayer Ceramic Capacitor, 1 µF, 25 V, 0402 [1005 Metric], ± 10%, X5R, GRM Series"
			(at 0 0 90)
			(layer "F.Fab")
			(hide yes)
			(effects
				(font
					(size 1.27 1.27)
					(thickness 0.15)
				)
			)
		)
		(property "MPN" "GRM155R61E105KE11J"
			(at 0 0 270)
			(unlocked yes)
			(layer "F.Fab")
			(hide yes)
			(effects
				(font
					(size 1 1)
					(thickness 0.15)
				)
			)
		)
		(property "Manufacturer" "Murata"
			(at 0 0 270)
			(unlocked yes)
			(layer "F.Fab")
			(hide yes)
			(effects
				(font
					(size 1 1)
					(thickness 0.15)
				)
			)
		)
		(property "License" "Apache-2.0"
			(at 0 0 270)
			(unlocked yes)
			(layer "F.Fab")
			(hide yes)
			(effects
				(font
					(size 1 1)
					(thickness 0.15)
				)
			)
		)
		(property "Author" "Antmicro"
			(at 0 0 270)
			(unlocked yes)
			(layer "F.Fab")
			(hide yes)
			(effects
				(font
					(size 1 1)
					(thickness 0.15)
				)
			)
		)
		(property "Val" "1u"
			(at 0 0 270)
			(unlocked yes)
			(layer "F.Fab")
			(hide yes)
			(effects
				(font
					(size 1 1)
					(thickness 0.15)
				)
			)
		)
		(property "Voltage" "25V"
			(at 0 0 270)
			(unlocked yes)
			(layer "F.Fab")
			(hide yes)
			(effects
				(font
					(size 1 1)
					(thickness 0.15)
				)
			)
		)
		(property "Dielectric" "X5R"
			(at 0 0 270)
			(unlocked yes)
			(layer "F.Fab")
			(hide yes)
			(effects
				(font
					(size 1 1)
					(thickness 0.15)
				)
			)
		)
		(sheetname "/Fan controller/")
		(sheetfile "fan-controller.kicad_sch")
		(attr smd exclude_from_pos_files exclude_from_bom dnp)
		(fp_rect
			(start -0.925 -0.47)
			(end 0.925 0.47)
			(stroke
				(width 0.05)
				(type default)
			)
			(fill no)
			(layer "F.CrtYd")
		)
		(fp_line
			(start -0.494 0.248)
			(end -0.494 -0.25)
			(stroke
				(width 0.15)
				(type solid)
			)
			(layer "F.Fab")
		)
		(fp_line
			(start 0.504 0.248)
			(end -0.494 0.248)
			(stroke
				(width 0.15)
				(type solid)
			)
			(layer "F.Fab")
		)
		(fp_line
			(start -0.494 -0.25)
			(end 0.504 -0.25)
			(stroke
				(width 0.15)
				(type solid)
			)
			(layer "F.Fab")
		)
		(fp_line
			(start 0.504 -0.25)
			(end 0.504 0.248)
			(stroke
				(width 0.15)
				(type solid)
			)
			(layer "F.Fab")
		)
		(fp_text user "Author: Antmicro"
			(at -0.939 3.399 90)
			(layer "F.Fab")
			(effects
				(font
					(size 0.7 0.7)
					(thickness 0.15)
				)
				(justify right top)
			)
		)
		(fp_text user "${REFERENCE}"
			(at -0.939 4.599 90)
			(layer "F.Fab")
			(effects
				(font
					(size 0.7 0.7)
					(thickness 0.15)
				)
				(justify right top)
			)
		)
		(fp_text user "License: Apache-2.0"
			(at -0.939 5.799 90)
			(layer "F.Fab")
			(effects
				(font
					(size 0.7 0.7)
					(thickness 0.15)
				)
				(justify right top)
			)
		)
		(pad "1" smd roundrect
			(at -0.48 0 270)
			(size 0.59 0.64)
			(layers "F.Cu" "F.Mask" "F.Paste")
			(roundrect_rratio 0.25)
			(net 28 "GND")
			(pintype "passive")
		)
		(pad "2" smd roundrect
			(at 0.48 0 270)
			(size 0.59 0.64)
			(layers "F.Cu" "F.Mask" "F.Paste")
			(roundrect_rratio 0.25)
			(net 314 "VCC")
			(pintype "passive")
		)
	)
	(footprint "antmicro-footprints:R_0402_1005Metric"
		(layer "F.Cu")
		(at 73.849999 77.039994 180)
		(descr "Resistor SMD 0402")
		(tags "resistor SMD 0402")
		(property "Reference" "R5"
			(at -1 3.439994 0)
			(layer "F.SilkS")
			(effects
				(font
					(size 0.7 0.7)
					(thickness 0.15)
				)
				(justify right top)
			)
		)
		(property "Value" "R_100k_0402"
			(at -1.011843 1.772046 0)
			(layer "F.Fab")
			(hide yes)
			(effects
				(font
					(size 0.7 0.7)
					(thickness 0.15)
				)
				(justify right top)
			)
		)
		(property "Datasheet" "https://www.bourns.com/docs/product-datasheets/cr.pdf"
			(at 0 0 0)
			(layer "F.Fab")
			(hide yes)
			(effects
				(font
					(size 1.27 1.27)
					(thickness 0.15)
				)
			)
		)
		(property "Description" "SMD Chip Resistor, 100 kohm, ± 1%, 62.5 mW, 0402 [1005 Metric], Thick Film, General Purpose"
			(at 0 0 0)
			(layer "F.Fab")
			(hide yes)
			(effects
				(font
					(size 1.27 1.27)
					(thickness 0.15)
				)
			)
		)
		(property "MPN" "CR0402-FX-1003GLF"
			(at 0 0 180)
			(unlocked yes)
			(layer "F.Fab")
			(hide yes)
			(effects
				(font
					(size 1 1)
					(thickness 0.15)
				)
			)
		)
		(property "Manufacturer" "Bourns"
			(at 0 0 180)
			(unlocked yes)
			(layer "F.Fab")
			(hide yes)
			(effects
				(font
					(size 1 1)
					(thickness 0.15)
				)
			)
		)
		(property "License" "Apache-2.0"
			(at 0 0 180)
			(unlocked yes)
			(layer "F.Fab")
			(hide yes)
			(effects
				(font
					(size 1 1)
					(thickness 0.15)
				)
			)
		)
		(property "Author" "Antmicro"
			(at 0 0 180)
			(unlocked yes)
			(layer "F.Fab")
			(hide yes)
			(effects
				(font
					(size 1 1)
					(thickness 0.15)
				)
			)
		)
		(property "Val" "100k"
			(at 0 0 180)
			(unlocked yes)
			(layer "F.Fab")
			(hide yes)
			(effects
				(font
					(size 1 1)
					(thickness 0.15)
				)
			)
		)
		(property "Tolerance" "1%"
			(at 0 0 180)
			(unlocked yes)
			(layer "F.Fab")
			(hide yes)
			(effects
				(font
					(size 1 1)
					(thickness 0.15)
				)
			)
		)
		(sheetname "/Power/")
		(sheetfile "power.kicad_sch")
		(attr smd)
		(fp_rect
			(start -0.925 -0.47)
			(end 0.925 0.47)
			(stroke
				(width 0.05)
				(type default)
			)
			(fill no)
			(layer "F.CrtYd")
		)
		(fp_rect
			(start -0.5 -0.25)
			(end 0.5 0.25)
			(stroke
				(width 0.15)
				(type solid)
			)
			(fill no)
			(layer "F.Fab")
		)
		(pad "1" smd roundrect
			(at -0.48 0 180)
			(size 0.59 0.64)
			(layers "F.Cu" "F.Mask" "F.Paste")
			(roundrect_rratio 0.25)
			(net 28 "GND")
			(pintype "passive")
		)
		(pad "2" smd roundrect
			(at 0.48 0 180)
			(size 0.59 0.64)
			(layers "F.Cu" "F.Mask" "F.Paste")
			(roundrect_rratio 0.25)
			(net 379 "/Power/3V3_EN")
			(pintype "passive")
		)
	)
	(footprint "antmicro-footprints:TP_SMD_0.75mm"
		(layer "F.Cu")
		(at 52.05 123.850001 180)
		(property "Reference" "TP19"
			(at 0.34 0.16 0)
			(layer "F.SilkS")
			(hide yes)
			(effects
				(font
					(size 0.7 0.7)
					(thickness 0.15)
				)
				(justify right top)
			)
		)
		(property "Value" "TP_0.75mm_SMD"
			(at 0 1.2 0)
			(layer "F.Fab")
			(hide yes)
			(effects
				(font
					(size 0.7 0.7)
					(thickness 0.15)
				)
				(justify right top)
			)
		)
		(property "Description" "SMT test point"
			(at 0 0 0)
			(layer "F.Fab")
			(hide yes)
			(effects
				(font
					(size 1.27 1.27)
					(thickness 0.15)
				)
			)
		)
		(property "MPN" ""
			(at 0 0 180)
			(unlocked yes)
			(layer "F.Fab")
			(hide yes)
			(effects
				(font
					(size 1 1)
					(thickness 0.15)
				)
			)
		)
		(property "Manufacturer" ""
			(at 0 0 180)
			(unlocked yes)
			(layer "F.Fab")
			(hide yes)
			(effects
				(font
					(size 1 1)
					(thickness 0.15)
				)
			)
		)
		(property "Author" "Antmicro"
			(at 0 0 180)
			(unlocked yes)
			(layer "F.Fab")
			(hide yes)
			(effects
				(font
					(size 1 1)
					(thickness 0.15)
				)
			)
		)
		(property "License" "Apache-2.0"
			(at 0 0 180)
			(unlocked yes)
			(layer "F.Fab")
			(hide yes)
			(effects
				(font
					(size 1 1)
					(thickness 0.15)
				)
			)
		)
		(sheetname "/Power/")
		(sheetfile "power.kicad_sch")
		(attr exclude_from_pos_files exclude_from_bom)
		(fp_circle
			(center 0 0)
			(end 0.475 0)
			(stroke
				(width 0.05)
				(type default)
			)
			(fill no)
			(layer "F.CrtYd")
		)
		(pad "1" smd circle
			(at 0 0 180)
			(size 0.75 0.75)
			(layers "F.Cu" "F.Mask")
			(net 310 "/Power/+1V88_OUT")
			(pinfunction "1")
			(pintype "passive")
		)
	)
	(footprint "antmicro-footprints:C_0402_1005Metric"
		(layer "F.Cu")
		(at 68.9 80.339994 -90)
		(descr "Capacitor SMD 0402")
		(tags "capacitor SMD 0402")
		(property "Reference" "C1"
			(at -2.279994 -0.58 270)
			(layer "F.SilkS")
			(effects
				(font
					(size 0.7 0.7)
					(thickness 0.15)
				)
				(justify right bottom)
			)
		)
		(property "Value" "C_100n_0402"
			(at -1.022927 2.155213 90)
			(layer "F.Fab")
			(hide yes)
			(effects
				(font
					(size 0.7 0.7)
					(thickness 0.15)
				)
				(justify right top)
			)
		)
		(property "Datasheet" "https://www.murata.com/products/productdetail?partno=GRM155R61H104KE14%23"
			(at 0 0 90)
			(layer "F.Fab")
			(hide yes)
			(effects
				(font
					(size 1.27 1.27)
					(thickness 0.15)
				)
			)
		)
		(property "Description" "SMD Multilayer Ceramic Capacitor, 0.1 µF, 50 V, 0402 [1005 Metric], ± 10%, X5R, GRM Series"
			(at 0 0 90)
			(layer "F.Fab")
			(hide yes)
			(effects
				(font
					(size 1.27 1.27)
					(thickness 0.15)
				)
			)
		)
		(property "MPN" "GRM155R61H104KE14D"
			(at 0 0 270)
			(unlocked yes)
			(layer "F.Fab")
			(hide yes)
			(effects
				(font
					(size 1 1)
					(thickness 0.15)
				)
			)
		)
		(property "Manufacturer" "Murata"
			(at 0 0 270)
			(unlocked yes)
			(layer "F.Fab")
			(hide yes)
			(effects
				(font
					(size 1 1)
					(thickness 0.15)
				)
			)
		)
		(property "License" "Apache-2.0"
			(at 0 0 270)
			(unlocked yes)
			(layer "F.Fab")
			(hide yes)
			(effects
				(font
					(size 1 1)
					(thickness 0.15)
				)
			)
		)
		(property "Author" "Antmicro"
			(at 0 0 270)
			(unlocked yes)
			(layer "F.Fab")
			(hide yes)
			(effects
				(font
					(size 1 1)
					(thickness 0.15)
				)
			)
		)
		(property "Val" "100n"
			(at 0 0 270)
			(unlocked yes)
			(layer "F.Fab")
			(hide yes)
			(effects
				(font
					(size 1 1)
					(thickness 0.15)
				)
			)
		)
		(property "Voltage" "50V"
			(at 0 0 270)
			(unlocked yes)
			(layer "F.Fab")
			(hide yes)
			(effects
				(font
					(size 1 1)
					(thickness 0.15)
				)
			)
		)
		(property "Dielectric" "X5R"
			(at 0 0 270)
			(unlocked yes)
			(layer "F.Fab")
			(hide yes)
			(effects
				(font
					(size 1 1)
					(thickness 0.15)
				)
			)
		)
		(sheetname "/Power/")
		(sheetfile "power.kicad_sch")
		(attr smd)
		(fp_rect
			(start -0.925 -0.47)
			(end 0.925 0.47)
			(stroke
				(width 0.05)
				(type default)
			)
			(fill no)
			(layer "F.CrtYd")
		)
		(fp_line
			(start -0.494 0.248)
			(end -0.494 -0.25)
			(stroke
				(width 0.15)
				(type solid)
			)
			(layer "F.Fab")
		)
		(fp_line
			(start 0.504 0.248)
			(end -0.494 0.248)
			(stroke
				(width 0.15)
				(type solid)
			)
			(layer "F.Fab")
		)
		(fp_line
			(start -0.494 -0.25)
			(end 0.504 -0.25)
			(stroke
				(width 0.15)
				(type solid)
			)
			(layer "F.Fab")
		)
		(fp_line
			(start 0.504 -0.25)
			(end 0.504 0.248)
			(stroke
				(width 0.15)
				(type solid)
			)
			(layer "F.Fab")
		)
		(pad "1" smd roundrect
			(at -0.48 0 270)
			(size 0.59 0.64)
			(layers "F.Cu" "F.Mask" "F.Paste")
			(roundrect_rratio 0.25)
			(net 316 "/Power/3V3_BST")
			(pintype "passive")
		)
		(pad "2" smd roundrect
			(at 0.48 0 270)
			(size 0.59 0.64)
			(layers "F.Cu" "F.Mask" "F.Paste")
			(roundrect_rratio 0.25)
			(net 333 "/Power/3V3_SW")
			(pintype "passive")
		)
	)
)
